(kicad_pcb
	(version 20260206)
	(generator "pcbnew")
	(generator_version "10.0")
	(general
		(thickness 1.6)
		(legacy_teardrops no)
	)
	(paper "A4")
	(title_block
		(title "9054_F0T_PDB_BD_GPU_F_V04_1213_1550_OCP.brd")
		(comment 1 "Grand Teton / footprints 362-368 of 608")
	)
	(layers
		(0 "F.Cu" signal "TOP")
		(4 "In1.Cu" signal "GND")
		(6 "In2.Cu" signal "IN1")
		(8 "In3.Cu" signal "GND1")
		(10 "In4.Cu" signal "VCC")
		(12 "In5.Cu" signal "VCC1")
		(14 "In6.Cu" signal "GND2")
		(16 "In7.Cu" signal "IN2")
		(18 "In8.Cu" signal "GND3")
		(2 "B.Cu" signal "BOTTOM")
		(9 "F.Adhes" user "F.Adhesive")
		(11 "B.Adhes" user "B.Adhesive")
		(13 "F.Paste" user "Package Geometry/Pastemask Top")
		(15 "B.Paste" user "Package Geometry/Pastemask Bottom")
		(5 "F.SilkS" user "Ref Des/Silkscreen Top")
		(7 "B.SilkS" user "Ref Des/Silkscreen Bottom")
		(1 "F.Mask" user "Board Geometry/Soldermask Top")
		(3 "B.Mask" user "Board Geometry/Soldermask Bottom")
		(17 "Dwgs.User" user "User.Drawings")
		(19 "Cmts.User" user "User.Comments")
		(21 "Eco1.User" user "User.Eco1")
		(23 "Eco2.User" user "User.Eco2")
		(25 "Edge.Cuts" user "Board Geometry/Outline")
		(27 "Margin" user)
		(31 "F.CrtYd" user "Package Geometry/Place Bound Top")
		(29 "B.CrtYd" user "Package Geometry/Place Bound Bottom")
		(35 "F.Fab" user "Ref Des/Assembly Top")
		(33 "B.Fab" user "Ref Des/Assembly Bottom")
	)
	(footprint ""
		(layer "F.Cu")
		(at 334.631284 -50.3428 -90)
		(property "Reference" "PR476"
			(at 0 0 270)
			(layer "F.SilkS")
			(hide yes)
			(effects
				(font
					(size 1.27 1.27)
				)
			)
		)
		(property "Value" ""
			(at 0 0 270)
			(layer "F.Fab")
			(effects
				(font
					(size 1.27 1.27)
				)
			)
		)
		(duplicate_pad_numbers_are_jumpers no)
		(fp_line
			(start -1.2954 0.5842)
			(end -1.2954 -0.5842)
			(stroke
				(width 0.1524)
				(type default)
			)
			(layer "F.SilkS")
		)
		(fp_line
			(start 1.2954 0.5842)
			(end -1.2954 0.5842)
			(stroke
				(width 0.1524)
				(type default)
			)
			(layer "F.SilkS")
		)
		(fp_line
			(start -1.2954 -0.5842)
			(end 1.2954 -0.5842)
			(stroke
				(width 0.1524)
				(type default)
			)
			(layer "F.SilkS")
		)
		(fp_line
			(start 1.2954 -0.5842)
			(end 1.2954 0.5842)
			(stroke
				(width 0.1524)
				(type default)
			)
			(layer "F.SilkS")
		)
		(fp_line
			(start -0.8636 0.4572)
			(end -0.8636 0.4318)
			(stroke
				(width 0.1)
				(type default)
			)
			(layer "F.Fab")
		)
		(fp_line
			(start 0.8636 0.4572)
			(end -0.8636 0.4572)
			(stroke
				(width 0.1)
				(type default)
			)
			(layer "F.Fab")
		)
		(fp_line
			(start -0.8636 0.4318)
			(end -0.8636 0.4064)
			(stroke
				(width 0.1)
				(type default)
			)
			(layer "F.Fab")
		)
		(fp_line
			(start -1.1938 0.4064)
			(end -1.1938 -0.406654)
			(stroke
				(width 0.1)
				(type default)
			)
			(layer "F.Fab")
		)
		(fp_line
			(start -0.8636 0.4064)
			(end -1.1938 0.4064)
			(stroke
				(width 0.1)
				(type default)
			)
			(layer "F.Fab")
		)
		(fp_line
			(start 0.8636 0.4064)
			(end 0.8636 0.4572)
			(stroke
				(width 0.1)
				(type default)
			)
			(layer "F.Fab")
		)
		(fp_line
			(start 1.1938 0.4064)
			(end 0.8636 0.4064)
			(stroke
				(width 0.1)
				(type default)
			)
			(layer "F.Fab")
		)
		(fp_line
			(start -1.1938 -0.406654)
			(end -0.8636 -0.406654)
			(stroke
				(width 0.1)
				(type default)
			)
			(layer "F.Fab")
		)
		(fp_line
			(start -0.8636 -0.406654)
			(end -0.8636 -0.4572)
			(stroke
				(width 0.1)
				(type default)
			)
			(layer "F.Fab")
		)
		(fp_line
			(start 0.8636 -0.406654)
			(end 1.1938 -0.406654)
			(stroke
				(width 0.1)
				(type default)
			)
			(layer "F.Fab")
		)
		(fp_line
			(start 1.1938 -0.406654)
			(end 1.1938 0.4064)
			(stroke
				(width 0.1)
				(type default)
			)
			(layer "F.Fab")
		)
		(fp_line
			(start -0.8636 -0.4572)
			(end 0.8636 -0.4572)
			(stroke
				(width 0.1)
				(type default)
			)
			(layer "F.Fab")
		)
		(fp_line
			(start 0.8636 -0.4572)
			(end 0.8636 -0.406654)
			(stroke
				(width 0.1)
				(type default)
			)
			(layer "F.Fab")
		)
		(pad "1" smd rect
			(at -0.7366 0 180)
			(size 0.7112 0.8128)
			(layers "F.Cu" "F.Mask" "F.Paste")
			(net "P52V_HS1_GATE1_R")
		)
		(pad "2" smd rect
			(at 0.7366 0 180)
			(size 0.7112 0.8128)
			(layers "F.Cu" "F.Mask" "F.Paste")
			(net "P52V_HS1_GATE3")
		)
	)
	(footprint ""
		(layer "F.Cu")
		(at 340.000336 -87.499952 180)
		(property "Reference" "H10"
			(at 0.910336 -5.484622 0)
			(unlocked yes)
			(layer "F.SilkS")
			(effects
				(font
					(size 0.7874 0.5842)
					(thickness 0.1524)
				)
				(justify left)
			)
		)
		(property "Value" ""
			(at 0 0 180)
			(layer "F.Fab")
			(effects
				(font
					(size 1.27 1.27)
				)
			)
		)
		(duplicate_pad_numbers_are_jumpers no)
		(pad "1" thru_hole oval
			(at 0 0 180)
			(size 9.017 14.0208)
			(drill 3.0226
				(offset 0 2.499868)
			)
			(layers "*.Cu" "*.Mask")
			(remove_unused_layers no)
			(net "GND")
			(clearance -1.500378)
			(padstack
				(mode front_inner_back)
				(layer "Inner"
					(shape circle)
					(size 0 0)
					(clearance 0)
				)
				(layer "B.Cu"
					(shape oval)
					(size 9.017 14.0208)
					(offset 0 2.499868)
					(clearance -1.500378)
				)
			)
		)
	)
	(footprint ""
		(layer "F.Cu")
		(at 419.93058 -32.75076 -90)
		(property "Reference" "R5917"
			(at 0 0 270)
			(layer "F.SilkS")
			(hide yes)
			(effects
				(font
					(size 1.27 1.27)
				)
			)
		)
		(property "Value" ""
			(at 0 0 270)
			(layer "F.Fab")
			(effects
				(font
					(size 1.27 1.27)
				)
			)
		)
		(duplicate_pad_numbers_are_jumpers no)
		(fp_line
			(start -0.7874 0.4064)
			(end -0.7874 -0.4064)
			(stroke
				(width 0.1524)
				(type default)
			)
			(layer "F.SilkS")
		)
		(fp_line
			(start 0.7874 0.4064)
			(end -0.7874 0.4064)
			(stroke
				(width 0.1524)
				(type default)
			)
			(layer "F.SilkS")
		)
		(fp_line
			(start -0.7874 -0.4064)
			(end 0.7874 -0.4064)
			(stroke
				(width 0.1524)
				(type default)
			)
			(layer "F.SilkS")
		)
		(fp_line
			(start 0.7874 -0.4064)
			(end 0.7874 0.4064)
			(stroke
				(width 0.1524)
				(type default)
			)
			(layer "F.SilkS")
		)
		(fp_line
			(start -0.67945 0.3048)
			(end -0.67945 -0.305054)
			(stroke
				(width 0.1)
				(type default)
			)
			(layer "F.Fab")
		)
		(fp_line
			(start -0.12065 0.3048)
			(end -0.67945 0.3048)
			(stroke
				(width 0.1)
				(type default)
			)
			(layer "F.Fab")
		)
		(fp_line
			(start 0.120396 0.3048)
			(end 0.120396 0.2794)
			(stroke
				(width 0.1)
				(type default)
			)
			(layer "F.Fab")
		)
		(fp_line
			(start 0.67945 0.3048)
			(end 0.120396 0.3048)
			(stroke
				(width 0.1)
				(type default)
			)
			(layer "F.Fab")
		)
		(fp_line
			(start -0.12065 0.2794)
			(end -0.12065 0.3048)
			(stroke
				(width 0.1)
				(type default)
			)
			(layer "F.Fab")
		)
		(fp_line
			(start 0.120396 0.2794)
			(end -0.12065 0.2794)
			(stroke
				(width 0.1)
				(type default)
			)
			(layer "F.Fab")
		)
		(fp_line
			(start -0.12065 -0.2794)
			(end 0.12065 -0.2794)
			(stroke
				(width 0.1)
				(type default)
			)
			(layer "F.Fab")
		)
		(fp_line
			(start 0.12065 -0.2794)
			(end 0.12065 -0.3048)
			(stroke
				(width 0.1)
				(type default)
			)
			(layer "F.Fab")
		)
		(fp_line
			(start 0.12065 -0.3048)
			(end 0.67945 -0.3048)
			(stroke
				(width 0.1)
				(type default)
			)
			(layer "F.Fab")
		)
		(fp_line
			(start 0.67945 -0.3048)
			(end 0.67945 0.3048)
			(stroke
				(width 0.1)
				(type default)
			)
			(layer "F.Fab")
		)
		(fp_line
			(start -0.67945 -0.305054)
			(end -0.12065 -0.305054)
			(stroke
				(width 0.1)
				(type default)
			)
			(layer "F.Fab")
		)
		(fp_line
			(start -0.12065 -0.305054)
			(end -0.12065 -0.2794)
			(stroke
				(width 0.1)
				(type default)
			)
			(layer "F.Fab")
		)
		(pad "1" smd circle
			(at -0.40005 0 270)
			(size 0 0)
			(layers "F.Cu" "F.Mask" "F.Paste")
			(net "P12V_LED_EN_BUF")
		)
		(pad "2" smd circle
			(at 0.40005 0 270)
			(size 0 0)
			(layers "F.Cu" "F.Mask" "F.Paste")
			(net "P12V_LED_EN_R")
		)
	)
	(footprint ""
		(layer "F.Cu")
		(at 449.199 -41.148 -90)
		(property "Reference" "R2"
			(at 0 0 270)
			(layer "F.SilkS")
			(hide yes)
			(effects
				(font
					(size 1.27 1.27)
				)
			)
		)
		(property "Value" ""
			(at 0 0 270)
			(layer "F.Fab")
			(effects
				(font
					(size 1.27 1.27)
				)
			)
		)
		(duplicate_pad_numbers_are_jumpers no)
		(fp_line
			(start -0.7874 0.4064)
			(end -0.7874 -0.4064)
			(stroke
				(width 0.1524)
				(type default)
			)
			(layer "F.SilkS")
		)
		(fp_line
			(start 0.7874 0.4064)
			(end -0.7874 0.4064)
			(stroke
				(width 0.1524)
				(type default)
			)
			(layer "F.SilkS")
		)
		(fp_line
			(start -0.7874 -0.4064)
			(end 0.7874 -0.4064)
			(stroke
				(width 0.1524)
				(type default)
			)
			(layer "F.SilkS")
		)
		(fp_line
			(start 0.7874 -0.4064)
			(end 0.7874 0.4064)
			(stroke
				(width 0.1524)
				(type default)
			)
			(layer "F.SilkS")
		)
		(fp_line
			(start -0.67945 0.3048)
			(end -0.67945 -0.305054)
			(stroke
				(width 0.1)
				(type default)
			)
			(layer "F.Fab")
		)
		(fp_line
			(start -0.12065 0.3048)
			(end -0.67945 0.3048)
			(stroke
				(width 0.1)
				(type default)
			)
			(layer "F.Fab")
		)
		(fp_line
			(start 0.120396 0.3048)
			(end 0.120396 0.2794)
			(stroke
				(width 0.1)
				(type default)
			)
			(layer "F.Fab")
		)
		(fp_line
			(start 0.67945 0.3048)
			(end 0.120396 0.3048)
			(stroke
				(width 0.1)
				(type default)
			)
			(layer "F.Fab")
		)
		(fp_line
			(start -0.12065 0.2794)
			(end -0.12065 0.3048)
			(stroke
				(width 0.1)
				(type default)
			)
			(layer "F.Fab")
		)
		(fp_line
			(start 0.120396 0.2794)
			(end -0.12065 0.2794)
			(stroke
				(width 0.1)
				(type default)
			)
			(layer "F.Fab")
		)
		(fp_line
			(start -0.12065 -0.2794)
			(end 0.12065 -0.2794)
			(stroke
				(width 0.1)
				(type default)
			)
			(layer "F.Fab")
		)
		(fp_line
			(start 0.12065 -0.2794)
			(end 0.12065 -0.3048)
			(stroke
				(width 0.1)
				(type default)
			)
			(layer "F.Fab")
		)
		(fp_line
			(start 0.12065 -0.3048)
			(end 0.67945 -0.3048)
			(stroke
				(width 0.1)
				(type default)
			)
			(layer "F.Fab")
		)
		(fp_line
			(start 0.67945 -0.3048)
			(end 0.67945 0.3048)
			(stroke
				(width 0.1)
				(type default)
			)
			(layer "F.Fab")
		)
		(fp_line
			(start -0.67945 -0.305054)
			(end -0.12065 -0.305054)
			(stroke
				(width 0.1)
				(type default)
			)
			(layer "F.Fab")
		)
		(fp_line
			(start -0.12065 -0.305054)
			(end -0.12065 -0.2794)
			(stroke
				(width 0.1)
				(type default)
			)
			(layer "F.Fab")
		)
		(pad "1" smd circle
			(at -0.40005 0 270)
			(size 0 0)
			(layers "F.Cu" "F.Mask" "F.Paste")
			(net "SMB_PDB_MISC_SDA_R")
		)
		(pad "2" smd circle
			(at 0.40005 0 270)
			(size 0 0)
			(layers "F.Cu" "F.Mask" "F.Paste")
			(net "P3V3_AUX")
		)
	)
	(footprint ""
		(layer "F.Cu")
		(at 42.36339 -78.74)
		(property "Reference" "PC44"
			(at 6.30301 -5.18033 0)
			(unlocked yes)
			(layer "F.SilkS")
			(effects
				(font
					(size 0.7874 0.5842)
					(thickness 0.1524)
				)
				(justify left)
			)
		)
		(property "Value" ""
			(at 0 0 0)
			(layer "F.Fab")
			(effects
				(font
					(size 1.27 1.27)
				)
			)
		)
		(duplicate_pad_numbers_are_jumpers no)
		(fp_line
			(start -9.253728 3.750056)
			(end 9.249918 3.750056)
			(stroke
				(width 0.1524)
				(type default)
			)
			(layer "F.SilkS")
		)
		(fp_line
			(start 0 3.750056)
			(end -9.253728 3.750056)
			(stroke
				(width 0.1524)
				(type default)
			)
			(layer "F.SilkS")
		)
		(fp_circle
			(center 0 3.750056)
			(end 9.249918 3.750056)
			(stroke
				(width 0.1524)
				(type default)
			)
			(fill no)
			(layer "F.SilkS")
		)
		(fp_poly
			(pts
				(arc
					(start 9.249918 3.750056)
					(mid 0 12.999974)
					(end -9.249918 3.750056)
				)
			)
			(stroke
				(width 0)
				(type default)
			)
			(fill yes)
			(layer "F.SilkS")
		)
		(fp_circle
			(center 0 3.750056)
			(end 9.249918 3.750056)
			(stroke
				(width 0.1)
				(type default)
			)
			(fill no)
			(layer "F.Fab")
		)
		(pad "1" thru_hole rect
			(at 0 0)
			(size 1.778 1.778)
			(drill 1.27)
			(layers "*.Cu" "*.Mask")
			(remove_unused_layers no)
			(net "P52V_HS2")
			(clearance 0)
			(padstack
				(mode front_inner_back)
				(layer "Inner"
					(shape circle)
					(size 1.778 1.778)
					(clearance 0)
				)
				(layer "B.Cu"
					(shape rect)
					(size 1.778 1.778)
					(clearance 0)
				)
			)
		)
		(pad "2" thru_hole circle
			(at 0 7.500112)
			(size 1.778 1.778)
			(drill 1.27)
			(layers "*.Cu" "*.Mask")
			(remove_unused_layers no)
			(net "GND")
			(clearance 0)
		)
	)
	(footprint ""
		(layer "F.Cu")
		(at 430.276 -44.577 180)
		(property "Reference" "R96"
			(at 0 0 180)
			(layer "F.SilkS")
			(hide yes)
			(effects
				(font
					(size 1.27 1.27)
				)
			)
		)
		(property "Value" ""
			(at 0 0 180)
			(layer "F.Fab")
			(effects
				(font
					(size 1.27 1.27)
				)
			)
		)
		(duplicate_pad_numbers_are_jumpers no)
		(fp_line
			(start 0.7874 0.4064)
			(end -0.7874 0.4064)
			(stroke
				(width 0.1524)
				(type default)
			)
			(layer "F.SilkS")
		)
		(fp_line
			(start 0.7874 -0.4064)
			(end 0.7874 0.4064)
			(stroke
				(width 0.1524)
				(type default)
			)
			(layer "F.SilkS")
		)
		(fp_line
			(start -0.7874 0.4064)
			(end -0.7874 -0.4064)
			(stroke
				(width 0.1524)
				(type default)
			)
			(layer "F.SilkS")
		)
		(fp_line
			(start -0.7874 -0.4064)
			(end 0.7874 -0.4064)
			(stroke
				(width 0.1524)
				(type default)
			)
			(layer "F.SilkS")
		)
		(fp_line
			(start 0.67945 0.3048)
			(end 0.120396 0.3048)
			(stroke
				(width 0.1)
				(type default)
			)
			(layer "F.Fab")
		)
		(fp_line
			(start 0.67945 -0.3048)
			(end 0.67945 0.3048)
			(stroke
				(width 0.1)
				(type default)
			)
			(layer "F.Fab")
		)
		(fp_line
			(start 0.12065 -0.2794)
			(end 0.12065 -0.3048)
			(stroke
				(width 0.1)
				(type default)
			)
			(layer "F.Fab")
		)
		(fp_line
			(start 0.12065 -0.3048)
			(end 0.67945 -0.3048)
			(stroke
				(width 0.1)
				(type default)
			)
			(layer "F.Fab")
		)
		(fp_line
			(start 0.120396 0.3048)
			(end 0.120396 0.2794)
			(stroke
				(width 0.1)
				(type default)
			)
			(layer "F.Fab")
		)
		(fp_line
			(start 0.120396 0.2794)
			(end -0.12065 0.2794)
			(stroke
				(width 0.1)
				(type default)
			)
			(layer "F.Fab")
		)
		(fp_line
			(start -0.12065 0.3048)
			(end -0.67945 0.3048)
			(stroke
				(width 0.1)
				(type default)
			)
			(layer "F.Fab")
		)
		(fp_line
			(start -0.12065 0.2794)
			(end -0.12065 0.3048)
			(stroke
				(width 0.1)
				(type default)
			)
			(layer "F.Fab")
		)
		(fp_line
			(start -0.12065 -0.2794)
			(end 0.12065 -0.2794)
			(stroke
				(width 0.1)
				(type default)
			)
			(layer "F.Fab")
		)
		(fp_line
			(start -0.12065 -0.305054)
			(end -0.12065 -0.2794)
			(stroke
				(width 0.1)
				(type default)
			)
			(layer "F.Fab")
		)
		(fp_line
			(start -0.67945 0.3048)
			(end -0.67945 -0.305054)
			(stroke
				(width 0.1)
				(type default)
			)
			(layer "F.Fab")
		)
		(fp_line
			(start -0.67945 -0.305054)
			(end -0.12065 -0.305054)
			(stroke
				(width 0.1)
				(type default)
			)
			(layer "F.Fab")
		)
		(pad "1" smd circle
			(at -0.40005 0 180)
			(size 0 0)
			(layers "F.Cu" "F.Mask" "F.Paste")
			(net "P3V3_AUX")
		)
		(pad "2" smd circle
			(at 0.40005 0 180)
			(size 0 0)
			(layers "F.Cu" "F.Mask" "F.Paste")
			(net "SKU_ID_2")
		)
	)
	(footprint ""
		(layer "F.Cu")
		(at 447.5734 -62.23 -90)
		(property "Reference" "PC50"
			(at 0 0 270)
			(layer "F.SilkS")
			(hide yes)
			(effects
				(font
					(size 1.27 1.27)
				)
			)
		)
		(property "Value" ""
			(at 0 0 270)
			(layer "F.Fab")
			(effects
				(font
					(size 1.27 1.27)
				)
			)
		)
		(duplicate_pad_numbers_are_jumpers no)
		(fp_line
			(start -1.524 0.762)
			(end -1.524 -0.762)
			(stroke
				(width 0.1524)
				(type default)
			)
			(layer "F.SilkS")
		)
		(fp_line
			(start 1.524 0.762)
			(end -1.524 0.762)
			(stroke
				(width 0.1524)
				(type default)
			)
			(layer "F.SilkS")
		)
		(fp_line
			(start -1.524 -0.762)
			(end 1.524 -0.762)
			(stroke
				(width 0.1524)
				(type default)
			)
			(layer "F.SilkS")
		)
		(fp_line
			(start 1.524 -0.762)
			(end 1.524 0.762)
			(stroke
				(width 0.1524)
				(type default)
			)
			(layer "F.SilkS")
		)
		(fp_line
			(start -1.1049 0.724916)
			(end 1.1049 0.724916)
			(stroke
				(width 0.1)
				(type default)
			)
			(layer "F.Fab")
		)
		(fp_line
			(start 1.1049 0.724916)
			(end 1.1049 -0.724916)
			(stroke
				(width 0.1)
				(type default)
			)
			(layer "F.Fab")
		)
		(fp_line
			(start -1.1049 -0.724916)
			(end -1.1049 0.724916)
			(stroke
				(width 0.1)
				(type default)
			)
			(layer "F.Fab")
		)
		(fp_line
			(start 1.1049 -0.724916)
			(end -1.1049 -0.724916)
			(stroke
				(width 0.1)
				(type default)
			)
			(layer "F.Fab")
		)
		(pad "1" smd rect
			(at -0.889 0 90)
			(size 1.016 1.27)
			(layers "F.Cu" "F.Mask" "F.Paste")
			(net "P3V3_AUX")
		)
		(pad "2" smd rect
			(at 0.889 0 90)
			(size 1.016 1.27)
			(layers "F.Cu" "F.Mask" "F.Paste")
			(net "GND")
		)
	)
)
